(kicad_pcb
	(version 20241229)
	(generator "pcbnew")
	(generator_version "9.0")
	(general
		(thickness 1.6)
		(legacy_teardrops no)
	)
	(paper "A4")
	(title_block
		(title "GMSL Deserializer")
		(date "2025-10-09")
		(rev "1.0.4")
		(company "Antmicro Ltd")
		(comment 1 "www.antmicro.com")
		(comment 9 "footprints 91-95 of 235")
	)
	(layers
		(0 "F.Cu" signal)
		(4 "In1.Cu" power)
		(6 "In2.Cu" power)
		(2 "B.Cu" signal)
		(9 "F.Adhes" user "F.Adhesive")
		(11 "B.Adhes" user "B.Adhesive")
		(13 "F.Paste" user)
		(15 "B.Paste" user)
		(5 "F.SilkS" user "F.Silkscreen")
		(7 "B.SilkS" user "B.Silkscreen")
		(1 "F.Mask" user)
		(3 "B.Mask" user)
		(17 "Dwgs.User" user "User.Drawings")
		(19 "Cmts.User" user "User.Comments")
		(21 "Eco1.User" user "User.Eco1")
		(23 "Eco2.User" user "User.Eco2")
		(25 "Edge.Cuts" user)
		(27 "Margin" user)
		(31 "F.CrtYd" user "F.Courtyard")
		(29 "B.CrtYd" user "B.Courtyard")
		(35 "F.Fab" user)
		(33 "B.Fab" user)
	)
	(footprint "antmicro-footprints:C_0402_1005Metric"
		(layer "F.Cu")
		(at 141.351 75.057 135)
		(descr "Capacitor SMD 0402")
		(tags "capacitor SMD 0402")
		(property "Reference" "C33"
			(at 6.272037 -0.486489 315)
			(unlocked yes)
			(layer "F.SilkS")
			(effects
				(font
					(size 0.7 0.7)
					(thickness 0.15)
				)
				(justify left bottom)
			)
		)
		(property "Value" "C_100n_0402"
			(at -1.022927 2.155213 135)
			(layer "F.Fab")
			(effects
				(font
					(size 0.7 0.7)
					(thickness 0.15)
				)
				(justify left bottom)
			)
		)
		(property "Datasheet" "https://www.murata.com/products/productdetail?partno=GRM155R61H104KE14%23"
			(at 0 0 135)
			(layer "F.Fab")
			(hide yes)
			(effects
				(font
					(size 1.27 1.27)
					(thickness 0.15)
				)
			)
		)
		(property "Description" "SMD Multilayer Ceramic Capacitor, 0.1 µF, 50 V, 0402 [1005 Metric], ± 10%, X5R, GRM Series"
			(at 0 0 135)
			(layer "F.Fab")
			(hide yes)
			(effects
				(font
					(size 1.27 1.27)
					(thickness 0.15)
				)
			)
		)
		(property "Author" "Antmicro"
			(at 294.374564 28.180063 0)
			(layer "F.Fab")
			(hide yes)
			(effects
				(font
					(size 1 1)
					(thickness 0.15)
				)
			)
		)
		(property "Dielectric" "X5R"
			(at 294.374564 28.180063 0)
			(layer "F.Fab")
			(hide yes)
			(effects
				(font
					(size 1 1)
					(thickness 0.15)
				)
			)
		)
		(property "License" "Apache-2.0"
			(at 294.374564 28.180063 0)
			(layer "F.Fab")
			(hide yes)
			(effects
				(font
					(size 1 1)
					(thickness 0.15)
				)
			)
		)
		(property "MPN" "GRM155R61H104KE14D"
			(at 294.374564 28.180063 0)
			(layer "F.Fab")
			(hide yes)
			(effects
				(font
					(size 1 1)
					(thickness 0.15)
				)
			)
		)
		(property "Manufacturer" "Murata"
			(at 294.374564 28.180063 0)
			(layer "F.Fab")
			(hide yes)
			(effects
				(font
					(size 1 1)
					(thickness 0.15)
				)
			)
		)
		(property "Val" "100n"
			(at 294.374564 28.180063 0)
			(layer "F.Fab")
			(hide yes)
			(effects
				(font
					(size 1 1)
					(thickness 0.15)
				)
			)
		)
		(property "Voltage" "50V"
			(at 294.374564 28.180063 0)
			(layer "F.Fab")
			(hide yes)
			(effects
				(font
					(size 1 1)
					(thickness 0.15)
				)
			)
		)
		(sheetname "/Deserializer/")
		(sheetfile "deserializer.kicad_sch")
		(attr smd)
		(fp_poly
			(pts
				(xy -0.925 -0.47) (xy 0.925 -0.47) (xy 0.925 0.47) (xy -0.925 0.47)
			)
			(stroke
				(width 0.05)
				(type default)
			)
			(fill no)
			(layer "F.CrtYd")
		)
		(fp_line
			(start 0.504 -0.25)
			(end 0.504 0.248)
			(stroke
				(width 0.15)
				(type solid)
			)
			(layer "F.Fab")
		)
		(fp_line
			(start 0.504 0.248)
			(end -0.494 0.248)
			(stroke
				(width 0.15)
				(type solid)
			)
			(layer "F.Fab")
		)
		(fp_line
			(start -0.494 -0.25)
			(end 0.504 -0.25)
			(stroke
				(width 0.15)
				(type solid)
			)
			(layer "F.Fab")
		)
		(fp_line
			(start -0.494 0.248)
			(end -0.494 -0.25)
			(stroke
				(width 0.15)
				(type solid)
			)
			(layer "F.Fab")
		)
		(pad "1" smd roundrect
			(at -0.48 0 135)
			(size 0.59 0.64)
			(layers "F.Cu" "F.Mask" "F.Paste")
			(roundrect_rratio 0.25)
			(net 20 "/Deserializer/SIOB_N")
			(pintype "passive")
		)
		(pad "2" smd roundrect
			(at 0.48 0 135)
			(size 0.59 0.64)
			(layers "F.Cu" "F.Mask" "F.Paste")
			(roundrect_rratio 0.25)
			(net 21 "Net-(C33-Pad2)")
			(pintype "passive")
		)
	)
	(footprint "antmicro-footprints:C_0402_1005Metric"
		(layer "F.Cu")
		(at 144.653 71.628 -90)
		(descr "Capacitor SMD 0402")
		(tags "capacitor SMD 0402")
		(property "Reference" "C57"
			(at -3.0226 -0.3302 90)
			(layer "F.SilkS")
			(effects
				(font
					(size 0.7 0.7)
					(thickness 0.15)
				)
				(justify right bottom)
			)
		)
		(property "Value" "C_33p_0402"
			(at -1.022927 2.155213 90)
			(layer "F.Fab")
			(effects
				(font
					(size 0.7 0.7)
					(thickness 0.15)
				)
				(justify right bottom)
			)
		)
		(property "Datasheet" "https://spicat.kyocera-avx.com/product/mlcc/chartview/04025A330FAT2A/"
			(at 0 0 270)
			(layer "F.Fab")
			(hide yes)
			(effects
				(font
					(size 1.27 1.27)
					(thickness 0.15)
				)
			)
		)
		(property "Description" "SMD Multilayer Ceramic Capacitor, 33 pF, 50 V, 0402 [1005 Metric], ± 5%, C0G / NP0, MC"
			(at 0 0 270)
			(layer "F.Fab")
			(hide yes)
			(effects
				(font
					(size 1.27 1.27)
					(thickness 0.15)
				)
			)
		)
		(property "Author" "Antmicro"
			(at 73.025 216.281 0)
			(layer "F.Fab")
			(hide yes)
			(effects
				(font
					(size 1 1)
					(thickness 0.15)
				)
			)
		)
		(property "Dielectric" ""
			(at 73.025 216.281 0)
			(layer "F.Fab")
			(hide yes)
			(effects
				(font
					(size 1 1)
					(thickness 0.15)
				)
			)
		)
		(property "License" "Apache-2.0"
			(at 73.025 216.281 0)
			(layer "F.Fab")
			(hide yes)
			(effects
				(font
					(size 1 1)
					(thickness 0.15)
				)
			)
		)
		(property "MPN" "04025A330FAT2A"
			(at 73.025 216.281 0)
			(layer "F.Fab")
			(hide yes)
			(effects
				(font
					(size 1 1)
					(thickness 0.15)
				)
			)
		)
		(property "Manufacturer" "KYOCERA AVX"
			(at 73.025 216.281 0)
			(layer "F.Fab")
			(hide yes)
			(effects
				(font
					(size 1 1)
					(thickness 0.15)
				)
			)
		)
		(property "Val" "33p"
			(at 73.025 216.281 0)
			(layer "F.Fab")
			(hide yes)
			(effects
				(font
					(size 1 1)
					(thickness 0.15)
				)
			)
		)
		(property "Voltage" ""
			(at 73.025 216.281 0)
			(layer "F.Fab")
			(hide yes)
			(effects
				(font
					(size 1 1)
					(thickness 0.15)
				)
			)
		)
		(sheetname "/Deserializer/")
		(sheetfile "deserializer.kicad_sch")
		(attr smd)
		(fp_rect
			(start -0.925 -0.47)
			(end 0.925 0.47)
			(stroke
				(width 0.05)
				(type default)
			)
			(fill no)
			(layer "F.CrtYd")
		)
		(fp_line
			(start -0.494 0.248)
			(end -0.494 -0.25)
			(stroke
				(width 0.15)
				(type solid)
			)
			(layer "F.Fab")
		)
		(fp_line
			(start 0.504 0.248)
			(end -0.494 0.248)
			(stroke
				(width 0.15)
				(type solid)
			)
			(layer "F.Fab")
		)
		(fp_line
			(start -0.494 -0.25)
			(end 0.504 -0.25)
			(stroke
				(width 0.15)
				(type solid)
			)
			(layer "F.Fab")
		)
		(fp_line
			(start 0.504 -0.25)
			(end 0.504 0.248)
			(stroke
				(width 0.15)
				(type solid)
			)
			(layer "F.Fab")
		)
		(pad "1" smd roundrect
			(at -0.48 0 270)
			(size 0.59 0.64)
			(layers "F.Cu" "F.Mask" "F.Paste")
			(roundrect_rratio 0.25)
			(net 1 "GND")
			(pintype "passive")
		)
		(pad "2" smd roundrect
			(at 0.48 0 270)
			(size 0.59 0.64)
			(layers "F.Cu" "F.Mask" "F.Paste")
			(roundrect_rratio 0.25)
			(net 17 "/Deserializer/X2_R")
			(pintype "passive")
		)
	)
	(footprint "antmicro-footprints:SOD-523_NP"
		(layer "F.Cu")
		(at 179.705 64.516 -90)
		(property "Reference" "D8"
			(at 8.636 -0.381 90)
			(layer "F.SilkS")
			(effects
				(font
					(size 0.7 0.7)
					(thickness 0.15)
				)
				(justify right bottom)
			)
		)
		(property "Value" "ESD5B5_0ST1G"
			(at 0 1.499 90)
			(layer "F.Fab")
			(effects
				(font
					(size 0.7 0.7)
					(thickness 0.15)
				)
				(justify right bottom)
			)
		)
		(property "Datasheet" "https://www.onsemi.com/pdf/datasheet/esd5b5.0st1-d.pdf"
			(at 0 0 270)
			(layer "F.Fab")
			(hide yes)
			(effects
				(font
					(size 1.27 1.27)
					(thickness 0.15)
				)
			)
		)
		(property "Description" "Bidirectional TVS, 30 kV,  SOD-523, 5 V, 32 pF"
			(at 0 0 270)
			(layer "F.Fab")
			(hide yes)
			(effects
				(font
					(size 1.27 1.27)
					(thickness 0.15)
				)
			)
		)
		(property "Author" "Antmicro"
			(at 115.189 244.221 0)
			(layer "F.Fab")
			(hide yes)
			(effects
				(font
					(size 1 1)
					(thickness 0.15)
				)
			)
		)
		(property "License" "Apache-2.0"
			(at 115.189 244.221 0)
			(layer "F.Fab")
			(hide yes)
			(effects
				(font
					(size 1 1)
					(thickness 0.15)
				)
			)
		)
		(property "MPN" "ESD5B5.0ST1G"
			(at 115.189 244.221 0)
			(layer "F.Fab")
			(hide yes)
			(effects
				(font
					(size 1 1)
					(thickness 0.15)
				)
			)
		)
		(property "Manufacturer" "ON Semiconductor"
			(at 115.189 244.221 0)
			(layer "F.Fab")
			(hide yes)
			(effects
				(font
					(size 1 1)
					(thickness 0.15)
				)
			)
		)
		(sheetname "/Connectors/")
		(sheetfile "connectors.kicad_sch")
		(attr smd)
		(fp_rect
			(start -1 -0.6)
			(end 1 0.6)
			(stroke
				(width 0.05)
				(type solid)
			)
			(fill no)
			(layer "F.CrtYd")
		)
		(fp_line
			(start -0.652 0.423)
			(end 0.65 0.423)
			(stroke
				(width 0.15)
				(type solid)
			)
			(layer "F.Fab")
		)
		(fp_line
			(start -0.652 0.423)
			(end -0.652 -0.425)
			(stroke
				(width 0.15)
				(type solid)
			)
			(layer "F.Fab")
		)
		(fp_line
			(start -0.652 -0.425)
			(end 0.65 -0.425)
			(stroke
				(width 0.15)
				(type solid)
			)
			(layer "F.Fab")
		)
		(fp_line
			(start 0.65 -0.425)
			(end 0.65 0.423)
			(stroke
				(width 0.15)
				(type solid)
			)
			(layer "F.Fab")
		)
		(pad "1" smd roundrect
			(at -0.701 0 270)
			(size 0.5 0.6)
			(layers "F.Cu" "F.Mask" "F.Paste")
			(roundrect_rratio 0.25)
			(net 1 "GND")
			(pinfunction "C")
			(pintype "passive")
		)
		(pad "2" smd roundrect
			(at 0.699 0 270)
			(size 0.5 0.6)
			(layers "F.Cu" "F.Mask" "F.Paste")
			(roundrect_rratio 0.25)
			(net 44 "/Connectors/SDA_CAM")
			(pinfunction "A")
			(pintype "passive")
		)
	)
	(footprint "antmicro-footprints:R_0402_1005Metric"
		(layer "F.Cu")
		(at 172.212 60.071 90)
		(descr "Resistor SMD 0402")
		(tags "resistor SMD 0402")
		(property "Reference" "R1"
			(at -0.813323 1.238 270)
			(layer "F.SilkS")
			(effects
				(font
					(size 0.7 0.7)
					(thickness 0.15)
				)
				(justify left bottom)
			)
		)
		(property "Value" "R_10k_0402"
			(at -1.011843 1.772047 90)
			(layer "F.Fab")
			(effects
				(font
					(size 0.7 0.7)
					(thickness 0.15)
				)
				(justify left bottom)
			)
		)
		(property "Datasheet" "https://www.bourns.com/docs/product-datasheets/cr.pdf"
			(at 0 0 90)
			(layer "F.Fab")
			(hide yes)
			(effects
				(font
					(size 1.27 1.27)
					(thickness 0.15)
				)
			)
		)
		(property "Description" "SMD Chip Resistor, 10 kohm, ± 1%, 62.5 mW, 0402 [1005 Metric], Thick Film, General Purpose"
			(at 0 0 90)
			(layer "F.Fab")
			(hide yes)
			(effects
				(font
					(size 1.27 1.27)
					(thickness 0.15)
				)
			)
		)
		(property "Author" "Antmicro"
			(at 232.283 -112.141 0)
			(layer "F.Fab")
			(hide yes)
			(effects
				(font
					(size 1 1)
					(thickness 0.15)
				)
			)
		)
		(property "License" "Apache-2.0"
			(at 232.283 -112.141 0)
			(layer "F.Fab")
			(hide yes)
			(effects
				(font
					(size 1 1)
					(thickness 0.15)
				)
			)
		)
		(property "MPN" "CR0402-FX-1002GLF"
			(at 232.283 -112.141 0)
			(layer "F.Fab")
			(hide yes)
			(effects
				(font
					(size 1 1)
					(thickness 0.15)
				)
			)
		)
		(property "Manufacturer" "Bourns"
			(at 232.283 -112.141 0)
			(layer "F.Fab")
			(hide yes)
			(effects
				(font
					(size 1 1)
					(thickness 0.15)
				)
			)
		)
		(property "Tolerance" "1%"
			(at 232.283 -112.141 0)
			(layer "F.Fab")
			(hide yes)
			(effects
				(font
					(size 1 1)
					(thickness 0.15)
				)
			)
		)
		(property "Val" "10k"
			(at 232.283 -112.141 0)
			(layer "F.Fab")
			(hide yes)
			(effects
				(font
					(size 1 1)
					(thickness 0.15)
				)
			)
		)
		(sheetname "/Connectors/")
		(sheetfile "connectors.kicad_sch")
		(attr smd)
		(fp_rect
			(start -0.925 -0.47)
			(end 0.925 0.47)
			(stroke
				(width 0.05)
				(type default)
			)
			(fill no)
			(layer "F.CrtYd")
		)
		(fp_rect
			(start -0.5 -0.25)
			(end 0.5 0.25)
			(stroke
				(width 0.15)
				(type solid)
			)
			(fill no)
			(layer "F.Fab")
		)
		(pad "1" smd roundrect
			(at -0.48 0 90)
			(size 0.59 0.64)
			(layers "F.Cu" "F.Mask" "F.Paste")
			(roundrect_rratio 0.25)
			(net 1 "GND")
			(pintype "passive")
		)
		(pad "2" smd roundrect
			(at 0.48 0 90)
			(size 0.59 0.64)
			(layers "F.Cu" "F.Mask" "F.Paste")
			(roundrect_rratio 0.25)
			(net 129 "Net-(U1-~{OE})")
			(pintype "passive")
		)
	)
	(footprint "antmicro-footprints:SOT-23-3"
		(layer "F.Cu")
		(at 179.324 52.832 -90)
		(property "Reference" "Q1"
			(at -1.016 -2.54 90)
			(layer "F.SilkS")
			(effects
				(font
					(size 0.7 0.7)
					(thickness 0.15)
				)
				(justify right bottom)
			)
		)
		(property "Value" "BSS138AKA"
			(at -1.9 2.7 90)
			(layer "F.Fab")
			(effects
				(font
					(size 0.7 0.7)
					(thickness 0.15)
				)
				(justify right bottom)
			)
		)
		(property "Datasheet" "https://www.onsemi.com/pub/Collateral/BSS138-D.PDF"
			(at 0 0 270)
			(layer "F.Fab")
			(hide yes)
			(effects
				(font
					(size 1.27 1.27)
					(thickness 0.15)
				)
			)
		)
		(property "Description" "Power MOSFET, N Channel, 50 V, 220 mA, 6.0 ohm, SOT-23, Surface Mount"
			(at 0 0 270)
			(layer "F.Fab")
			(hide yes)
			(effects
				(font
					(size 1.27 1.27)
					(thickness 0.15)
				)
			)
		)
		(property "Author" "Antmicro"
			(at 126.492 232.156 0)
			(layer "F.Fab")
			(hide yes)
			(effects
				(font
					(size 1 1)
					(thickness 0.15)
				)
			)
		)
		(property "License" "Apache-2.0"
			(at 126.492 232.156 0)
			(layer "F.Fab")
			(hide yes)
			(effects
				(font
					(size 1 1)
					(thickness 0.15)
				)
			)
		)
		(property "MPN" "BSS138AKA"
			(at 126.492 232.156 0)
			(layer "F.Fab")
			(hide yes)
			(effects
				(font
					(size 1 1)
					(thickness 0.15)
				)
			)
		)
		(property "Manufacturer" "ON Semiconductor"
			(at 126.492 232.156 0)
			(layer "F.Fab")
			(hide yes)
			(effects
				(font
					(size 1 1)
					(thickness 0.15)
				)
			)
		)
		(sheetname "/Power/")
		(sheetfile "power.kicad_sch")
		(attr smd)
		(fp_line
			(start -0.7 1.5)
			(end -0.7 1.35)
			(stroke
				(width 0.15)
				(type solid)
			)
			(layer "F.SilkS")
		)
		(fp_line
			(start 0.7 1.5)
			(end -0.7 1.5)
			(stroke
				(width 0.15)
				(type solid)
			)
			(layer "F.SilkS")
		)
		(fp_line
			(start 0.7 0.4)
			(end 0.7 1.5)
			(stroke
				(width 0.15)
				(type solid)
			)
			(layer "F.SilkS")
		)
		(fp_line
			(start 0.7 -0.4)
			(end 0.7 -1.5)
			(stroke
				(width 0.15)
				(type solid)
			)
			(layer "F.SilkS")
		)
		(fp_line
			(start -1.45 -1.35)
			(end -0.85 -1.35)
			(stroke
				(width 0.15)
				(type solid)
			)
			(layer "F.SilkS")
		)
		(fp_line
			(start -0.85 -1.35)
			(end -0.7 -1.5)
			(stroke
				(width 0.15)
				(type solid)
			)
			(layer "F.SilkS")
		)
		(fp_line
			(start 0.7 -1.5)
			(end -0.7 -1.5)
			(stroke
				(width 0.15)
				(type solid)
			)
			(layer "F.SilkS")
		)
		(fp_line
			(start -0.85 1.65)
			(end -0.85 1.4)
			(stroke
				(width 0.05)
				(type solid)
			)
			(layer "F.CrtYd")
		)
		(fp_line
			(start 0.85 1.65)
			(end -0.85 1.65)
			(stroke
				(width 0.05)
				(type solid)
			)
			(layer "F.CrtYd")
		)
		(fp_line
			(start -1.75 1.4)
			(end -1.75 0.5)
			(stroke
				(width 0.05)
				(type solid)
			)
			(layer "F.CrtYd")
		)
		(fp_line
			(start -0.85 1.4)
			(end -1.75 1.4)
			(stroke
				(width 0.05)
				(type solid)
			)
			(layer "F.CrtYd")
		)
		(fp_line
			(start -1.75 0.5)
			(end -0.85 0.5)
			(stroke
				(width 0.05)
				(type solid)
			)
			(layer "F.CrtYd")
		)
		(fp_line
			(start -0.85 0.5)
			(end -0.85 -0.5)
			(stroke
				(width 0.05)
				(type solid)
			)
			(layer "F.CrtYd")
		)
		(fp_line
			(start 0.85 0.45)
			(end 0.85 1.65)
			(stroke
				(width 0.05)
				(type solid)
			)
			(layer "F.CrtYd")
		)
		(fp_line
			(start 1.75 0.45)
			(end 0.85 0.45)
			(stroke
				(width 0.05)
				(type solid)
			)
			(layer "F.CrtYd")
		)
		(fp_line
			(start 0.825 -0.45)
			(end 1.75 -0.45)
			(stroke
				(width 0.05)
				(type solid)
			)
			(layer "F.CrtYd")
		)
		(fp_line
			(start 1.75 -0.45)
			(end 1.75 0.45)
			(stroke
				(width 0.05)
				(type solid)
			)
			(layer "F.CrtYd")
		)
		(fp_line
			(start -1.75 -0.5)
			(end -1.75 -1.4)
			(stroke
				(width 0.05)
				(type solid)
			)
			(layer "F.CrtYd")
		)
		(fp_line
			(start -0.85 -0.5)
			(end -1.75 -0.5)
			(stroke
				(width 0.05)
				(type solid)
			)
			(layer "F.CrtYd")
		)
		(fp_line
			(start -0.9 -1.4)
			(end -1.75 -1.4)
			(stroke
				(width 0.05)
				(type solid)
			)
			(layer "F.CrtYd")
		)
		(fp_line
			(start -0.9 -1.6)
			(end -0.9 -1.4)
			(stroke
				(width 0.05)
				(type solid)
			)
			(layer "F.CrtYd")
		)
		(fp_line
			(start -0.9 -1.6)
			(end 0.825 -1.6)
			(stroke
				(width 0.05)
				(type solid)
			)
			(layer "F.CrtYd")
		)
		(fp_line
			(start 0.825 -1.6)
			(end 0.825 -0.45)
			(stroke
				(width 0.05)
				(type solid)
			)
			(layer "F.CrtYd")
		)
		(fp_line
			(start -0.712 1.519)
			(end 0.688 1.519)
			(stroke
				(width 0.15)
				(type solid)
			)
			(layer "F.Fab")
		)
		(fp_line
			(start 0.688 1.519)
			(end 0.688 -1.52)
			(stroke
				(width 0.15)
				(type solid)
			)
			(layer "F.Fab")
		)
		(fp_line
			(start -0.712 -1.325)
			(end -0.712 1.523)
			(stroke
				(width 0.15)
				(type solid)
			)
			(layer "F.Fab")
		)
		(fp_line
			(start -0.437 -1.526)
			(end -0.712 -1.325)
			(stroke
				(width 0.15)
				(type solid)
			)
			(layer "F.Fab")
		)
		(fp_line
			(start -0.437 -1.526)
			(end 0.688 -1.526)
			(stroke
				(width 0.15)
				(type solid)
			)
			(layer "F.Fab")
		)
		(pad "1" smd roundrect
			(at -1.1 -0.951 270)
			(size 1 0.6)
			(layers "F.Cu" "F.Mask" "F.Paste")
			(roundrect_rratio 0.15)
			(net 126 "Net-(Q1-G)")
			(pinfunction "G")
			(pintype "input")
		)
		(pad "2" smd roundrect
			(at -1.1 0.949 270)
			(size 1 0.6)
			(layers "F.Cu" "F.Mask" "F.Paste")
			(roundrect_rratio 0.15)
			(net 1 "GND")
			(pinfunction "S")
			(pintype "passive")
		)
		(pad "3" smd roundrect
			(at 1.1 -0.0005 270)
			(size 1 0.6)
			(layers "F.Cu" "F.Mask" "F.Paste")
			(roundrect_rratio 0.15)
			(net 63 "/Power/FFC_5V_EN")
			(pinfunction "D")
			(pintype "passive")
		)
	)
)
